# T6G (Grand Teton) — schematic netlist excerpt (pin names and nets, part order shuffled) for the footprints in the layout excerpt that follows; sources: Cadence DE-HDL packaged netlist, KiCad conversion of 04192023_DAF0TMB3IC0_F0TG_MB_C_brd_V02_OCP.brd

PR454  Q_RES  12.4K 1% CHIP  pkg 0402LF  page 192 : A = PVDD_33_S5_FB ; B = GND
PC113  Q_CAP  0.1UF 25V 10% X7R  pkg 0402  page 209 : A = PVDD18_S5_P0_REF ; B = PVDD18_S5_P0_RGND
R965  Q_RES  1K 1% EMPTY  pkg 0201LF  page 276 : A = RT_CPU0_P0_ADDR3 ; B = GND

(kicad_pcb
	(version 20260206)
	(generator "pcbnew")
	(generator_version "10.0")
	(general
		(thickness 1.6)
		(legacy_teardrops no)
	)
	(paper "A4")
	(title_block
		(title "04192023_DAF0TMB3IC0_F0TG_MB_C_brd_V02_OCP.brd")
		(comment 1 "Grand Teton / footprints 2795-2797 of 8354")
	)
	(layers
		(0 "F.Cu" signal "TOP")
		(4 "In1.Cu" signal "GND")
		(6 "In2.Cu" signal "IN1")
		(8 "In3.Cu" signal "GND1")
		(10 "In4.Cu" signal "IN2")
		(12 "In5.Cu" signal "GND2")
		(14 "In6.Cu" signal "IN3")
		(16 "In7.Cu" signal "GND3")
		(18 "In8.Cu" signal "VCC")
		(20 "In9.Cu" signal "VCC1")
		(22 "In10.Cu" signal "GND4")
		(24 "In11.Cu" signal "IN4")
		(26 "In12.Cu" signal "GND5")
		(28 "In13.Cu" signal "IN5")
		(30 "In14.Cu" signal "GND6")
		(32 "In15.Cu" signal "IN6")
		(34 "In16.Cu" signal "GND7")
		(2 "B.Cu" signal "BOTTOM")
		(9 "F.Adhes" user "F.Adhesive")
		(11 "B.Adhes" user "B.Adhesive")
		(13 "F.Paste" user "Package Geometry/Pastemask Top")
		(15 "B.Paste" user "Package Geometry/Pastemask Bottom")
		(5 "F.SilkS" user "Ref Des/Silkscreen Top")
		(7 "B.SilkS" user "Ref Des/Silkscreen Bottom")
		(1 "F.Mask" user "Board Geometry/Soldermask Top")
		(3 "B.Mask" user "Board Geometry/Soldermask Bottom")
		(17 "Dwgs.User" user "User.Drawings")
		(19 "Cmts.User" user "User.Comments")
		(21 "Eco1.User" user "User.Eco1")
		(23 "Eco2.User" user "User.Eco2")
		(25 "Edge.Cuts" user "Board Geometry/Outline")
		(27 "Margin" user)
		(31 "F.CrtYd" user "Package Geometry/Place Bound Top")
		(29 "B.CrtYd" user "Package Geometry/Place Bound Bottom")
		(35 "F.Fab" user "Ref Des/Assembly Top")
		(33 "B.Fab" user "Ref Des/Assembly Bottom")
	)
	(footprint ""
		(layer "F.Cu")
		(at 332.070964 -140.008102 -90)
		(property "Reference" "PC113"
			(at 0 0 270)
			(layer "F.SilkS")
			(hide yes)
			(effects
				(font
					(size 1.27 1.27)
				)
			)
		)
		(property "Value" ""
			(at 0 0 270)
			(layer "F.Fab")
			(effects
				(font
					(size 1.27 1.27)
				)
			)
		)
		(duplicate_pad_numbers_are_jumpers no)
		(fp_line
			(start -0.7874 0.4064)
			(end -0.7874 -0.4064)
			(stroke
				(width 0.1524)
				(type default)
			)
			(layer "F.SilkS")
		)
		(fp_line
			(start 0.7874 0.4064)
			(end -0.7874 0.4064)
			(stroke
				(width 0.1524)
				(type default)
			)
			(layer "F.SilkS")
		)
		(fp_line
			(start -0.7874 -0.4064)
			(end 0.7874 -0.4064)
			(stroke
				(width 0.1524)
				(type default)
			)
			(layer "F.SilkS")
		)
		(fp_line
			(start 0.7874 -0.4064)
			(end 0.7874 0.4064)
			(stroke
				(width 0.1524)
				(type default)
			)
			(layer "F.SilkS")
		)
		(fp_line
			(start -0.67945 0.3048)
			(end -0.67945 -0.305054)
			(stroke
				(width 0.1)
				(type default)
			)
			(layer "F.Fab")
		)
		(fp_line
			(start -0.12065 0.3048)
			(end -0.67945 0.3048)
			(stroke
				(width 0.1)
				(type default)
			)
			(layer "F.Fab")
		)
		(fp_line
			(start 0.120396 0.3048)
			(end 0.120396 0.2794)
			(stroke
				(width 0.1)
				(type default)
			)
			(layer "F.Fab")
		)
		(fp_line
			(start 0.67945 0.3048)
			(end 0.120396 0.3048)
			(stroke
				(width 0.1)
				(type default)
			)
			(layer "F.Fab")
		)
		(fp_line
			(start -0.12065 0.2794)
			(end -0.12065 0.3048)
			(stroke
				(width 0.1)
				(type default)
			)
			(layer "F.Fab")
		)
		(fp_line
			(start 0.120396 0.2794)
			(end -0.12065 0.2794)
			(stroke
				(width 0.1)
				(type default)
			)
			(layer "F.Fab")
		)
		(fp_line
			(start -0.12065 -0.2794)
			(end 0.12065 -0.2794)
			(stroke
				(width 0.1)
				(type default)
			)
			(layer "F.Fab")
		)
		(fp_line
			(start 0.12065 -0.2794)
			(end 0.12065 -0.3048)
			(stroke
				(width 0.1)
				(type default)
			)
			(layer "F.Fab")
		)
		(fp_line
			(start 0.12065 -0.3048)
			(end 0.67945 -0.3048)
			(stroke
				(width 0.1)
				(type default)
			)
			(layer "F.Fab")
		)
		(fp_line
			(start 0.67945 -0.3048)
			(end 0.67945 0.3048)
			(stroke
				(width 0.1)
				(type default)
			)
			(layer "F.Fab")
		)
		(fp_line
			(start -0.67945 -0.305054)
			(end -0.12065 -0.305054)
			(stroke
				(width 0.1)
				(type default)
			)
			(layer "F.Fab")
		)
		(fp_line
			(start -0.12065 -0.305054)
			(end -0.12065 -0.2794)
			(stroke
				(width 0.1)
				(type default)
			)
			(layer "F.Fab")
		)
		(pad "1" smd circle
			(at -0.40005 0 270)
			(size 0 0)
			(layers "F.Cu" "F.Mask" "F.Paste")
			(net "PVDD18_S5_P0_REF")
		)
		(pad "2" smd circle
			(at 0.40005 0 270)
			(size 0 0)
			(layers "F.Cu" "F.Mask" "F.Paste")
			(net "PVDD18_S5_P0_RGND")
		)
	)
	(footprint ""
		(layer "F.Cu")
		(at 327.881742 -395.1732 90)
		(property "Reference" "R965"
			(at 0 0 90)
			(layer "F.SilkS")
			(hide yes)
			(effects
				(font
					(size 1.27 1.27)
				)
			)
		)
		(property "Value" ""
			(at 0 0 90)
			(layer "F.Fab")
			(effects
				(font
					(size 1.27 1.27)
				)
			)
		)
		(duplicate_pad_numbers_are_jumpers no)
		(fp_line
			(start 0.32512 -0.175006)
			(end 0.32512 0.175006)
			(stroke
				(width 0.1)
				(type default)
			)
			(layer "F.Fab")
		)
		(fp_line
			(start -0.32512 -0.175006)
			(end 0.32512 -0.175006)
			(stroke
				(width 0.1)
				(type default)
			)
			(layer "F.Fab")
		)
		(fp_line
			(start 0.32512 0.175006)
			(end -0.32512 0.175006)
			(stroke
				(width 0.1)
				(type default)
			)
			(layer "F.Fab")
		)
		(fp_line
			(start -0.32512 0.175006)
			(end -0.32512 -0.175006)
			(stroke
				(width 0.1)
				(type default)
			)
			(layer "F.Fab")
		)
		(pad "1" smd rect
			(at -0.2667 0 90)
			(size 0.3048 0.381)
			(layers "F.Cu" "F.Mask" "F.Paste")
			(net "RT_CPU0_P0_ADDR3")
		)
		(pad "2" smd rect
			(at 0.2667 0 270)
			(size 0.3048 0.381)
			(layers "F.Cu" "F.Mask" "F.Paste")
			(net "GND")
		)
	)
	(footprint ""
		(layer "F.Cu")
		(at 204.331824 -342.075262 -90.054)
		(property "Reference" "PR454"
			(at 0 0 269.946)
			(layer "F.SilkS")
			(hide yes)
			(effects
				(font
					(size 1.27 1.27)
				)
			)
		)
		(property "Value" ""
			(at 0 0 269.946)
			(layer "F.Fab")
			(effects
				(font
					(size 1.27 1.27)
				)
			)
		)
		(duplicate_pad_numbers_are_jumpers no)
		(fp_line
			(start 0.787275 0.40642)
			(end -0.787525 0.40638)
			(stroke
				(width 0.1524)
				(type default)
			)
			(layer "F.SilkS")
		)
		(fp_line
			(start -0.787525 0.40638)
			(end -0.787275 -0.40642)
			(stroke
				(width 0.1524)
				(type default)
			)
			(layer "F.SilkS")
		)
		(fp_line
			(start 0.787525 -0.40638)
			(end 0.787275 0.40642)
			(stroke
				(width 0.1524)
				(type default)
			)
			(layer "F.SilkS")
		)
		(fp_line
			(start -0.787275 -0.40642)
			(end 0.787525 -0.40638)
			(stroke
				(width 0.1524)
				(type default)
			)
			(layer "F.SilkS")
		)
		(fp_line
			(start 0.679484 0.304922)
			(end 0.120429 0.304687)
			(stroke
				(width 0.1)
				(type default)
			)
			(layer "F.Fab")
		)
		(fp_line
			(start -0.120617 0.304914)
			(end -0.679417 0.304678)
			(stroke
				(width 0.1)
				(type default)
			)
			(layer "F.Fab")
		)
		(fp_line
			(start 0.120429 0.304687)
			(end 0.120405 0.279287)
			(stroke
				(width 0.1)
				(type default)
			)
			(layer "F.Fab")
		)
		(fp_line
			(start -0.679417 0.304678)
			(end -0.679484 -0.305176)
			(stroke
				(width 0.1)
				(type default)
			)
			(layer "F.Fab")
		)
		(fp_line
			(start -0.120641 0.279514)
			(end -0.120617 0.304914)
			(stroke
				(width 0.1)
				(type default)
			)
			(layer "F.Fab")
		)
		(fp_line
			(start 0.120405 0.279287)
			(end -0.120641 0.279514)
			(stroke
				(width 0.1)
				(type default)
			)
			(layer "F.Fab")
		)
		(fp_line
			(start -0.120659 -0.279286)
			(end 0.120641 -0.279514)
			(stroke
				(width 0.1)
				(type default)
			)
			(layer "F.Fab")
		)
		(fp_line
			(start 0.120641 -0.279514)
			(end 0.120617 -0.304914)
			(stroke
				(width 0.1)
				(type default)
			)
			(layer "F.Fab")
		)
		(fp_line
			(start 0.679417 -0.304678)
			(end 0.679484 0.304922)
			(stroke
				(width 0.1)
				(type default)
			)
			(layer "F.Fab")
		)
		(fp_line
			(start 0.120617 -0.304914)
			(end 0.679417 -0.304678)
			(stroke
				(width 0.1)
				(type default)
			)
			(layer "F.Fab")
		)
		(fp_line
			(start -0.120683 -0.30494)
			(end -0.120659 -0.279286)
			(stroke
				(width 0.1)
				(type default)
			)
			(layer "F.Fab")
		)
		(fp_line
			(start -0.679484 -0.305176)
			(end -0.120683 -0.30494)
			(stroke
				(width 0.1)
				(type default)
			)
			(layer "F.Fab")
		)
		(pad "1" smd circle
			(at -0.40005 0 269.946)
			(size 0 0)
			(layers "F.Cu" "F.Mask" "F.Paste")
			(net "PVDD_33_S5_FB")
		)
		(pad "2" smd circle
			(at 0.40005 0 269.946)
			(size 0 0)
			(layers "F.Cu" "F.Mask" "F.Paste")
			(net "GND")
		)
	)
)
